# T6G (Grand Teton) — schematic netlist excerpt (pin names and nets, part order shuffled) for the footprints in the layout excerpt that follows; sources: Cadence DE-HDL packaged netlist, KiCad conversion of 04192023_DAF0TMB3IC0_F0TG_MB_C_brd_V02_OCP.brd

PU51  ISL99390FRZTR5935  ISL99390FRZ-TR5935 IC  pkg QFN21_6X5XB  page 199
  VOS  = PVDDCR_SOC_P0_VOS3
  AGND  = GND
  VCC  = PVDDCR_SOC_P0_VCC3
  PVCC  = PVDDCR_CPU0_P0_PVCC
  PGND1  = GND
  GL1  = NC_PVDDCR_SOC_P0_GL1_3
  PGND2  = GND
  SW  = SW_PVDDCR_SOC_P0_SW3
  VIN1  = SW_P12V_AUX_PVDDCR_SOC_P0_FLT
  VIN2  = SW_P12V_AUX_PVDDCR_SOC_P0_FLT
  DNC  = NC_PVDDCR_SOC_P0_DNC3
  PHASE  = SW_PVDDCR_SOC_P0_PH3
  BOOT  = SW_PVDDCR_SOC_P0_BOOT3
  PWM  = PVDDCR_SOC_P0_PWM3
  EN  = PVDDCR_SOC_P0_VCC3
  TOUT_FLT  = PVDDCR_SOC_P0_TEMP1
  LSET  = PVDDCR_SOC_P0_LSET3
  IOUT  = PVDDCR_SOC_P0_IMON3
  REFIN  = PVDDCR_CPU0_P0_VCCS
  PGND3  = GND
  GL2  = NC_PVDDCR_SOC_P0_GL2_3

(kicad_pcb
	(version 20260206)
	(generator "pcbnew")
	(generator_version "10.0")
	(general
		(thickness 1.6)
		(legacy_teardrops no)
	)
	(paper "A4")
	(title_block
		(title "04192023_DAF0TMB3IC0_F0TG_MB_C_brd_V02_OCP.brd")
		(comment 1 "Grand Teton / footprints 3543-3543 of 8354")
	)
	(layers
		(0 "F.Cu" signal "TOP")
		(4 "In1.Cu" signal "GND")
		(6 "In2.Cu" signal "IN1")
		(8 "In3.Cu" signal "GND1")
		(10 "In4.Cu" signal "IN2")
		(12 "In5.Cu" signal "GND2")
		(14 "In6.Cu" signal "IN3")
		(16 "In7.Cu" signal "GND3")
		(18 "In8.Cu" signal "VCC")
		(20 "In9.Cu" signal "VCC1")
		(22 "In10.Cu" signal "GND4")
		(24 "In11.Cu" signal "IN4")
		(26 "In12.Cu" signal "GND5")
		(28 "In13.Cu" signal "IN5")
		(30 "In14.Cu" signal "GND6")
		(32 "In15.Cu" signal "IN6")
		(34 "In16.Cu" signal "GND7")
		(2 "B.Cu" signal "BOTTOM")
		(9 "F.Adhes" user "F.Adhesive")
		(11 "B.Adhes" user "B.Adhesive")
		(13 "F.Paste" user "Package Geometry/Pastemask Top")
		(15 "B.Paste" user "Package Geometry/Pastemask Bottom")
		(5 "F.SilkS" user "Ref Des/Silkscreen Top")
		(7 "B.SilkS" user "Ref Des/Silkscreen Bottom")
		(1 "F.Mask" user "Board Geometry/Soldermask Top")
		(3 "B.Mask" user "Board Geometry/Soldermask Bottom")
		(17 "Dwgs.User" user "User.Drawings")
		(19 "Cmts.User" user "User.Comments")
		(21 "Eco1.User" user "User.Eco1")
		(23 "Eco2.User" user "User.Eco2")
		(25 "Edge.Cuts" user "Board Geometry/Outline")
		(27 "Margin" user)
		(31 "F.CrtYd" user "Package Geometry/Place Bound Top")
		(29 "B.CrtYd" user "Package Geometry/Place Bound Bottom")
		(35 "F.Fab" user "Ref Des/Assembly Top")
		(33 "B.Fab" user "Ref Des/Assembly Bottom")
	)
	(footprint ""
		(layer "F.Cu")
		(at 414.529778 -163.76777 180)
		(property "Reference" "PU51"
			(at 5.373624 -4.878324 0)
			(unlocked yes)
			(layer "F.SilkS")
			(effects
				(font
					(size 0.7874 0.5842)
					(thickness 0.1524)
				)
				(justify left)
			)
		)
		(property "Value" ""
			(at 0 0 180)
			(layer "F.Fab")
			(effects
				(font
					(size 1.27 1.27)
				)
			)
		)
		(duplicate_pad_numbers_are_jumpers no)
		(fp_line
			(start 2.500122 2.999994)
			(end 2.2987 2.999994)
			(stroke
				(width 0.1524)
				(type default)
			)
			(layer "F.SilkS")
		)
		(fp_line
			(start 2.500122 2.339594)
			(end 2.500122 2.999994)
			(stroke
				(width 0.1524)
				(type default)
			)
			(layer "F.SilkS")
		)
		(fp_line
			(start 2.500122 -2.999994)
			(end 2.500122 -2.44348)
			(stroke
				(width 0.1524)
				(type default)
			)
			(layer "F.SilkS")
		)
		(fp_line
			(start 2.31394 -2.999994)
			(end 2.500122 -2.999994)
			(stroke
				(width 0.1524)
				(type default)
			)
			(layer "F.SilkS")
		)
		(fp_line
			(start -2.2987 2.999994)
			(end -2.500122 2.999994)
			(stroke
				(width 0.1524)
				(type default)
			)
			(layer "F.SilkS")
		)
		(fp_line
			(start -2.500122 2.999994)
			(end -2.500122 2.339594)
			(stroke
				(width 0.1524)
				(type default)
			)
			(layer "F.SilkS")
		)
		(fp_line
			(start -2.500122 0.6604)
			(end -2.500122 0.229108)
			(stroke
				(width 0.1524)
				(type default)
			)
			(layer "F.SilkS")
		)
		(fp_line
			(start -2.500122 -2.529078)
			(end -2.500122 -2.999994)
			(stroke
				(width 0.1524)
				(type default)
			)
			(layer "F.SilkS")
		)
		(fp_line
			(start -2.500122 -2.999994)
			(end -2.24409 -2.999994)
			(stroke
				(width 0.1524)
				(type default)
			)
			(layer "F.SilkS")
		)
		(fp_poly
			(pts
				(xy -2.637028 -2.515362) (xy -3.35026 -2.753106) (xy -2.874518 -3.228594)
			)
			(stroke
				(width 0)
				(type default)
			)
			(fill yes)
			(layer "F.SilkS")
		)
		(fp_line
			(start 2.500122 2.999994)
			(end -2.500122 2.999994)
			(stroke
				(width 0.1)
				(type default)
			)
			(layer "F.Fab")
		)
		(fp_line
			(start 2.500122 -2.999994)
			(end 2.500122 2.999994)
			(stroke
				(width 0.1)
				(type default)
			)
			(layer "F.Fab")
		)
		(fp_line
			(start -2.500122 2.999994)
			(end -2.500122 -2.999994)
			(stroke
				(width 0.1)
				(type default)
			)
			(layer "F.Fab")
		)
		(fp_line
			(start -2.500122 -2.999994)
			(end 2.500122 -2.999994)
			(stroke
				(width 0.1)
				(type default)
			)
			(layer "F.Fab")
		)
		(fp_poly
			(pts
				(xy -4.218432 -2.783078) (xy -4.218432 -1.767078) (xy -3.202432 -2.275078)
			)
			(stroke
				(width 0)
				(type default)
			)
			(fill yes)
			(layer "F.Fab")
		)
		(pad "1" smd rect
			(at -2.400046 -2.275078 270)
			(size 0.2286 0.6096)
			(layers "F.Cu" "F.Mask" "F.Paste")
			(net "PVDDCR_SOC_P0_VOS3")
		)
		(pad "2" smd rect
			(at -2.400046 -1.82499 270)
			(size 0.2286 0.6096)
			(layers "F.Cu" "F.Mask" "F.Paste")
			(net "GND")
		)
		(pad "3" smd rect
			(at -2.400046 -1.374902 270)
			(size 0.2286 0.6096)
			(layers "F.Cu" "F.Mask" "F.Paste")
			(net "PVDDCR_SOC_P0_VCC3")
		)
		(pad "4" smd rect
			(at -2.400046 -0.925068 270)
			(size 0.2286 0.6096)
			(layers "F.Cu" "F.Mask" "F.Paste")
			(net "PVDDCR_CPU0_P0_PVCC")
		)
		(pad "5" smd rect
			(at -2.400046 -0.47498 270)
			(size 0.2286 0.6096)
			(layers "F.Cu" "F.Mask" "F.Paste")
			(net "GND")
		)
		(pad "6" smd rect
			(at -2.400046 -0.024892 270)
			(size 0.2286 0.6096)
			(layers "F.Cu" "F.Mask" "F.Paste")
			(net "NC_PVDDCR_SOC_P0_GL1_3")
		)
		(pad "7_9-20_24" smd circle
			(at 0 1.150112 270)
			(size 0 0)
			(layers "F.Cu" "F.Mask" "F.Paste")
			(net "GND")
		)
		(pad "10_19" smd rect
			(at 0 2.899918 270)
			(size 0.6096 4.318)
			(layers "F.Cu" "F.Mask" "F.Paste")
			(net "SW_PVDDCR_SOC_P0_SW3")
		)
		(pad "25_29" smd rect
			(at 1.549908 -1.279906 90)
			(size 2.0574 2.3114)
			(layers "F.Cu" "F.Mask" "F.Paste")
			(net "SW_P12V_AUX_PVDDCR_SOC_P0_FLT")
		)
		(pad "30" smd rect
			(at 2.05994 -2.899918 180)
			(size 0.2286 0.6096)
			(layers "F.Cu" "F.Mask" "F.Paste")
			(net "SW_P12V_AUX_PVDDCR_SOC_P0_FLT")
		)
		(pad "31" smd rect
			(at 1.610106 -2.899918 180)
			(size 0.2286 0.6096)
			(layers "F.Cu" "F.Mask" "F.Paste")
			(net "NC_PVDDCR_SOC_P0_DNC3")
		)
		(pad "32" smd rect
			(at 1.160018 -2.899918 180)
			(size 0.2286 0.6096)
			(layers "F.Cu" "F.Mask" "F.Paste")
			(net "SW_PVDDCR_SOC_P0_PH3")
		)
		(pad "33" smd rect
			(at 0.70993 -2.899918 180)
			(size 0.2286 0.6096)
			(layers "F.Cu" "F.Mask" "F.Paste")
			(net "SW_PVDDCR_SOC_P0_BOOT3")
		)
		(pad "34" smd rect
			(at 0.260096 -2.899918 180)
			(size 0.2286 0.6096)
			(layers "F.Cu" "F.Mask" "F.Paste")
			(net "PVDDCR_SOC_P0_PWM3")
		)
		(pad "35" smd rect
			(at -0.189992 -2.899918 180)
			(size 0.2286 0.6096)
			(layers "F.Cu" "F.Mask" "F.Paste")
			(net "PVDDCR_SOC_P0_VCC3")
		)
		(pad "36" smd rect
			(at -0.64008 -2.899918 180)
			(size 0.2286 0.6096)
			(layers "F.Cu" "F.Mask" "F.Paste")
			(net "PVDDCR_SOC_P0_TEMP1")
		)
		(pad "37" smd rect
			(at -1.089914 -2.899918 180)
			(size 0.2286 0.6096)
			(layers "F.Cu" "F.Mask" "F.Paste")
			(net "PVDDCR_SOC_P0_LSET3")
		)
		(pad "38" smd rect
			(at -1.540002 -2.899918 180)
			(size 0.2286 0.6096)
			(layers "F.Cu" "F.Mask" "F.Paste")
			(net "PVDDCR_SOC_P0_IMON3")
		)
		(pad "39" smd rect
			(at -1.99009 -2.899918 180)
			(size 0.2286 0.6096)
			(layers "F.Cu" "F.Mask" "F.Paste")
			(net "PVDDCR_CPU0_P0_VCCS")
		)
		(pad "40" smd rect
			(at -0.87503 -1.27508 180)
			(size 1.7526 1.9558)
			(layers "F.Cu" "F.Mask" "F.Paste")
			(net "GND")
		)
		(pad "41" smd rect
			(at -1.525016 0.249936 90)
			(size 0.3048 0.4572)
			(layers "F.Cu" "F.Mask" "F.Paste")
			(net "NC_PVDDCR_SOC_P0_GL2_3")
		)
		(zone
			(layer "F.Cu")
			(hatch none 0.5)
			(connect_pads
				(clearance 0)
			)
			(min_thickness 0.25)
			(keepout
				(tracks not_allowed)
				(vias allowed)
				(pads allowed)
				(copperpour not_allowed)
				(footprints allowed)
			)
			(placement
				(enabled no)
				(sheetname "")
			)
			(fill
				(thermal_gap 0.5)
				(thermal_bridge_width 0.5)
				(island_removal_mode 0)
			)
			(polygon
				(pts
					(xy 417.0299 -166.345108) (xy 417.0299 -166.018464) (xy 412.029656 -166.018464) (xy 412.029656 -166.331646)
					(xy 412.319978 -166.331646) (xy 412.319978 -166.312088) (xy 416.739578 -166.312088) (xy 416.739578 -166.345108)
				)
			)
		)
		(zone
			(layer "F.Cu")
			(hatch none 0.5)
			(connect_pads
				(clearance 0)
			)
			(min_thickness 0.25)
			(keepout
				(tracks not_allowed)
				(vias allowed)
				(pads allowed)
				(copperpour not_allowed)
				(footprints allowed)
			)
			(placement
				(enabled no)
				(sheetname "")
			)
			(fill
				(thermal_gap 0.5)
				(thermal_bridge_width 0.5)
				(island_removal_mode 0)
			)
			(polygon
				(pts
					(xy 414.477708 -163.52139) (xy 414.477708 -161.46399) (xy 416.331908 -161.46399) (xy 416.331908 -161.705036)
					(xy 416.574224 -161.705036) (xy 416.574224 -161.223452) (xy 412.722822 -161.223452) (xy 412.722822 -161.408364)
					(xy 414.18637 -161.408364) (xy 414.18637 -163.567364) (xy 412.029656 -163.567364) (xy 412.029656 -163.817046)
					(xy 414.182052 -163.817046)
				)
			)
		)
	)
)
